(kicad_pcb
	(version 20260206)
	(generator "pcbnew")
	(generator_version "10.0")
	(general
		(thickness 1.6)
		(legacy_teardrops no)
	)
	(paper "A4")
	(title_block
		(title "03242023_DA0F0TMBIJ0_F0T_Motherboard_J_brd_V01_OCP.brd")
		(comment 1 "Grand Teton / footprints 257-261 of 6105")
	)
	(layers
		(0 "F.Cu" signal "TOP")
		(4 "In1.Cu" signal "GND")
		(6 "In2.Cu" signal "IN1")
		(8 "In3.Cu" signal "GND1")
		(10 "In4.Cu" signal "IN2")
		(12 "In5.Cu" signal "GND2")
		(14 "In6.Cu" signal "IN3")
		(16 "In7.Cu" signal "GND3")
		(18 "In8.Cu" signal "VCC")
		(20 "In9.Cu" signal "VCC1")
		(22 "In10.Cu" signal "GND4")
		(24 "In11.Cu" signal "IN4")
		(26 "In12.Cu" signal "GND5")
		(28 "In13.Cu" signal "IN5")
		(30 "In14.Cu" signal "GND6")
		(32 "In15.Cu" signal "IN6")
		(34 "In16.Cu" signal "GND7")
		(2 "B.Cu" signal "BOTTOM")
		(9 "F.Adhes" user "F.Adhesive")
		(11 "B.Adhes" user "B.Adhesive")
		(13 "F.Paste" user "Package Geometry/Pastemask Top")
		(15 "B.Paste" user "Package Geometry/Pastemask Bottom")
		(5 "F.SilkS" user "Ref Des/Silkscreen Top")
		(7 "B.SilkS" user "Ref Des/Silkscreen Bottom")
		(1 "F.Mask" user "Board Geometry/Soldermask Top")
		(3 "B.Mask" user "Board Geometry/Soldermask Bottom")
		(17 "Dwgs.User" user "User.Drawings")
		(19 "Cmts.User" user "User.Comments")
		(21 "Eco1.User" user "User.Eco1")
		(23 "Eco2.User" user "User.Eco2")
		(25 "Edge.Cuts" user "Board Geometry/Outline")
		(27 "Margin" user)
		(31 "F.CrtYd" user "Package Geometry/Place Bound Top")
		(29 "B.CrtYd" user "Package Geometry/Place Bound Bottom")
		(35 "F.Fab" user "Ref Des/Assembly Top")
		(33 "B.Fab" user "Ref Des/Assembly Bottom")
	)
	(footprint ""
		(layer "F.Cu")
		(at 153.21788 -112.867948 180)
		(property "Reference" "R3235"
			(at 0 0 180)
			(layer "F.SilkS")
			(hide yes)
			(effects
				(font
					(size 1.27 1.27)
				)
			)
		)
		(property "Value" ""
			(at 0 0 180)
			(layer "F.Fab")
			(effects
				(font
					(size 1.27 1.27)
				)
			)
		)
		(duplicate_pad_numbers_are_jumpers no)
		(fp_line
			(start 0.7874 0.4064)
			(end -0.7874 0.4064)
			(stroke
				(width 0.1524)
				(type default)
			)
			(layer "F.SilkS")
		)
		(fp_line
			(start 0.7874 -0.4064)
			(end 0.7874 0.4064)
			(stroke
				(width 0.1524)
				(type default)
			)
			(layer "F.SilkS")
		)
		(fp_line
			(start -0.7874 0.4064)
			(end -0.7874 -0.4064)
			(stroke
				(width 0.1524)
				(type default)
			)
			(layer "F.SilkS")
		)
		(fp_line
			(start -0.7874 -0.4064)
			(end 0.7874 -0.4064)
			(stroke
				(width 0.1524)
				(type default)
			)
			(layer "F.SilkS")
		)
		(fp_line
			(start 0.67945 0.3048)
			(end 0.120396 0.3048)
			(stroke
				(width 0.1)
				(type default)
			)
			(layer "F.Fab")
		)
		(fp_line
			(start 0.67945 -0.3048)
			(end 0.67945 0.3048)
			(stroke
				(width 0.1)
				(type default)
			)
			(layer "F.Fab")
		)
		(fp_line
			(start 0.12065 -0.2794)
			(end 0.12065 -0.3048)
			(stroke
				(width 0.1)
				(type default)
			)
			(layer "F.Fab")
		)
		(fp_line
			(start 0.12065 -0.3048)
			(end 0.67945 -0.3048)
			(stroke
				(width 0.1)
				(type default)
			)
			(layer "F.Fab")
		)
		(fp_line
			(start 0.120396 0.3048)
			(end 0.120396 0.2794)
			(stroke
				(width 0.1)
				(type default)
			)
			(layer "F.Fab")
		)
		(fp_line
			(start 0.120396 0.2794)
			(end -0.12065 0.2794)
			(stroke
				(width 0.1)
				(type default)
			)
			(layer "F.Fab")
		)
		(fp_line
			(start -0.12065 0.3048)
			(end -0.67945 0.3048)
			(stroke
				(width 0.1)
				(type default)
			)
			(layer "F.Fab")
		)
		(fp_line
			(start -0.12065 0.2794)
			(end -0.12065 0.3048)
			(stroke
				(width 0.1)
				(type default)
			)
			(layer "F.Fab")
		)
		(fp_line
			(start -0.12065 -0.2794)
			(end 0.12065 -0.2794)
			(stroke
				(width 0.1)
				(type default)
			)
			(layer "F.Fab")
		)
		(fp_line
			(start -0.12065 -0.305054)
			(end -0.12065 -0.2794)
			(stroke
				(width 0.1)
				(type default)
			)
			(layer "F.Fab")
		)
		(fp_line
			(start -0.67945 0.3048)
			(end -0.67945 -0.305054)
			(stroke
				(width 0.1)
				(type default)
			)
			(layer "F.Fab")
		)
		(fp_line
			(start -0.67945 -0.305054)
			(end -0.12065 -0.305054)
			(stroke
				(width 0.1)
				(type default)
			)
			(layer "F.Fab")
		)
		(pad "1" smd circle
			(at -0.40005 0 180)
			(size 0 0)
			(layers "F.Cu" "F.Mask" "F.Paste")
			(net "RST_HP_OCP_V3_2_R_N")
		)
		(pad "2" smd circle
			(at 0.40005 0 180)
			(size 0 0)
			(layers "F.Cu" "F.Mask" "F.Paste")
			(net "GND")
		)
	)
	(footprint ""
		(layer "F.Cu")
		(at 416.009582 -170.821858 -90)
		(property "Reference" "PU43_P0_1"
			(at -4.59486 -6.229858 0)
			(unlocked yes)
			(layer "F.SilkS")
			(effects
				(font
					(size 0.7874 0.5842)
					(thickness 0.1524)
				)
				(justify left)
			)
		)
		(property "Value" ""
			(at 0 0 270)
			(layer "F.Fab")
			(effects
				(font
					(size 1.27 1.27)
				)
			)
		)
		(duplicate_pad_numbers_are_jumpers no)
		(fp_line
			(start -2.500122 2.999994)
			(end -2.500122 2.339594)
			(stroke
				(width 0.1524)
				(type default)
			)
			(layer "F.SilkS")
		)
		(fp_line
			(start -2.2987 2.999994)
			(end -2.500122 2.999994)
			(stroke
				(width 0.1524)
				(type default)
			)
			(layer "F.SilkS")
		)
		(fp_line
			(start 2.500122 2.999994)
			(end 2.2987 2.999994)
			(stroke
				(width 0.1524)
				(type default)
			)
			(layer "F.SilkS")
		)
		(fp_line
			(start 2.500122 2.339594)
			(end 2.500122 2.999994)
			(stroke
				(width 0.1524)
				(type default)
			)
			(layer "F.SilkS")
		)
		(fp_line
			(start -2.500122 0.6604)
			(end -2.500122 0.229108)
			(stroke
				(width 0.1524)
				(type default)
			)
			(layer "F.SilkS")
		)
		(fp_line
			(start -2.500122 -2.529078)
			(end -2.500122 -2.999994)
			(stroke
				(width 0.1524)
				(type default)
			)
			(layer "F.SilkS")
		)
		(fp_line
			(start -2.500122 -2.999994)
			(end -2.24409 -2.999994)
			(stroke
				(width 0.1524)
				(type default)
			)
			(layer "F.SilkS")
		)
		(fp_line
			(start 2.31394 -2.999994)
			(end 2.500122 -2.999994)
			(stroke
				(width 0.1524)
				(type default)
			)
			(layer "F.SilkS")
		)
		(fp_line
			(start 2.500122 -2.999994)
			(end 2.500122 -2.44348)
			(stroke
				(width 0.1524)
				(type default)
			)
			(layer "F.SilkS")
		)
		(fp_poly
			(pts
				(xy -4.215892 -2.236978) (xy -5.231892 -1.728978) (xy -5.231892 -2.744978)
			)
			(stroke
				(width 0)
				(type default)
			)
			(fill yes)
			(layer "F.SilkS")
		)
		(fp_line
			(start -2.500122 2.999994)
			(end -2.500122 -2.999994)
			(stroke
				(width 0.1)
				(type default)
			)
			(layer "F.Fab")
		)
		(fp_line
			(start 2.500122 2.999994)
			(end -2.500122 2.999994)
			(stroke
				(width 0.1)
				(type default)
			)
			(layer "F.Fab")
		)
		(fp_line
			(start -2.500122 -2.999994)
			(end 2.500122 -2.999994)
			(stroke
				(width 0.1)
				(type default)
			)
			(layer "F.Fab")
		)
		(fp_line
			(start 2.500122 -2.999994)
			(end 2.500122 2.999994)
			(stroke
				(width 0.1)
				(type default)
			)
			(layer "F.Fab")
		)
		(fp_poly
			(pts
				(xy -4.218432 -2.783078) (xy -4.218432 -1.767078) (xy -3.202432 -2.275078)
			)
			(stroke
				(width 0)
				(type default)
			)
			(fill yes)
			(layer "F.Fab")
		)
		(pad "1" smd rect
			(at -2.400046 -2.275078)
			(size 0.2286 0.6096)
			(layers "F.Cu" "F.Mask" "F.Paste")
			(net "PVCCINFAON_CPU0_VOS1")
		)
		(pad "2" smd rect
			(at -2.400046 -1.82499)
			(size 0.2286 0.6096)
			(layers "F.Cu" "F.Mask" "F.Paste")
			(net "GND")
		)
		(pad "3" smd rect
			(at -2.400046 -1.374902)
			(size 0.2286 0.6096)
			(layers "F.Cu" "F.Mask" "F.Paste")
			(net "PVCCINFAON_CPU0_VDD1")
		)
		(pad "4" smd rect
			(at -2.400046 -0.925068)
			(size 0.2286 0.6096)
			(layers "F.Cu" "F.Mask" "F.Paste")
			(net "PVCCFA_EHV_CPU0_PVCC")
		)
		(pad "5" smd rect
			(at -2.400046 -0.47498)
			(size 0.2286 0.6096)
			(layers "F.Cu" "F.Mask" "F.Paste")
			(net "GND")
		)
		(pad "6" smd rect
			(at -2.400046 -0.024892)
			(size 0.2286 0.6096)
			(layers "F.Cu" "F.Mask" "F.Paste")
			(net "Net_1923")
		)
		(pad "7_9-20_24" smd circle
			(at 0 1.150112)
			(size 0 0)
			(layers "F.Cu" "F.Mask" "F.Paste")
			(net "GND")
		)
		(pad "10_19" smd rect
			(at 0 2.899918)
			(size 0.6096 4.318)
			(layers "F.Cu" "F.Mask" "F.Paste")
			(net "SW_PVCCINFAON_CPU0_SW1")
		)
		(pad "25_29" smd rect
			(at 1.549908 -1.279906 180)
			(size 2.0574 2.3114)
			(layers "F.Cu" "F.Mask" "F.Paste")
			(net "SW_P12V_PVCCINFAON_CPU0_FLT")
		)
		(pad "30" smd rect
			(at 2.05994 -2.899918 270)
			(size 0.2286 0.6096)
			(layers "F.Cu" "F.Mask" "F.Paste")
			(net "SW_P12V_PVCCINFAON_CPU0_FLT")
		)
		(pad "31" smd rect
			(at 1.610106 -2.899918 270)
			(size 0.2286 0.6096)
			(layers "F.Cu" "F.Mask" "F.Paste")
			(net "Net_1922")
		)
		(pad "32" smd rect
			(at 1.160018 -2.899918 270)
			(size 0.2286 0.6096)
			(layers "F.Cu" "F.Mask" "F.Paste")
			(net "SW_PVCCINFAON_CPU0_BOOTR1")
		)
		(pad "33" smd rect
			(at 0.70993 -2.899918 270)
			(size 0.2286 0.6096)
			(layers "F.Cu" "F.Mask" "F.Paste")
			(net "SW_PVCCINFAON_CPU0_BOOT1")
		)
		(pad "34" smd rect
			(at 0.260096 -2.899918 270)
			(size 0.2286 0.6096)
			(layers "F.Cu" "F.Mask" "F.Paste")
			(net "PVCCINFAON_CPU0_APWM1")
		)
		(pad "35" smd rect
			(at -0.189992 -2.899918 270)
			(size 0.2286 0.6096)
			(layers "F.Cu" "F.Mask" "F.Paste")
			(net "PVCCINFAON_CPU0_VDD1")
		)
		(pad "36" smd rect
			(at -0.64008 -2.899918 270)
			(size 0.2286 0.6096)
			(layers "F.Cu" "F.Mask" "F.Paste")
			(net "PVCCINFAON_CPU0_ATSEN")
		)
		(pad "37" smd rect
			(at -1.089914 -2.899918 270)
			(size 0.2286 0.6096)
			(layers "F.Cu" "F.Mask" "F.Paste")
			(net "PVCCINFAON_CPU0_LSET1")
		)
		(pad "38" smd rect
			(at -1.540002 -2.899918 270)
			(size 0.2286 0.6096)
			(layers "F.Cu" "F.Mask" "F.Paste")
			(net "PVCCINFAON_CPU0_ACSP1")
		)
		(pad "39" smd rect
			(at -1.99009 -2.899918 270)
			(size 0.2286 0.6096)
			(layers "F.Cu" "F.Mask" "F.Paste")
			(net "PVCCINFAON_CPU0_VREF")
		)
		(pad "40" smd rect
			(at -0.87503 -1.27508 270)
			(size 1.7526 1.9558)
			(layers "F.Cu" "F.Mask" "F.Paste")
			(net "GND")
		)
		(pad "41" smd rect
			(at -1.525016 0.249936 180)
			(size 0.3048 0.4572)
			(layers "F.Cu" "F.Mask" "F.Paste")
			(net "Net_1924")
		)
	)
	(footprint ""
		(layer "F.Cu")
		(at 139.2682 -104.116378 -90)
		(property "Reference" "R338"
			(at 0 0 270)
			(layer "F.SilkS")
			(hide yes)
			(effects
				(font
					(size 1.27 1.27)
				)
			)
		)
		(property "Value" ""
			(at 0 0 270)
			(layer "F.Fab")
			(effects
				(font
					(size 1.27 1.27)
				)
			)
		)
		(duplicate_pad_numbers_are_jumpers no)
		(fp_line
			(start -0.7874 0.4064)
			(end -0.7874 -0.4064)
			(stroke
				(width 0.1524)
				(type default)
			)
			(layer "F.SilkS")
		)
		(fp_line
			(start 0.7874 0.4064)
			(end -0.7874 0.4064)
			(stroke
				(width 0.1524)
				(type default)
			)
			(layer "F.SilkS")
		)
		(fp_line
			(start -0.7874 -0.4064)
			(end 0.7874 -0.4064)
			(stroke
				(width 0.1524)
				(type default)
			)
			(layer "F.SilkS")
		)
		(fp_line
			(start 0.7874 -0.4064)
			(end 0.7874 0.4064)
			(stroke
				(width 0.1524)
				(type default)
			)
			(layer "F.SilkS")
		)
		(fp_line
			(start -0.67945 0.3048)
			(end -0.67945 -0.305054)
			(stroke
				(width 0.1)
				(type default)
			)
			(layer "F.Fab")
		)
		(fp_line
			(start -0.12065 0.3048)
			(end -0.67945 0.3048)
			(stroke
				(width 0.1)
				(type default)
			)
			(layer "F.Fab")
		)
		(fp_line
			(start 0.120396 0.3048)
			(end 0.120396 0.2794)
			(stroke
				(width 0.1)
				(type default)
			)
			(layer "F.Fab")
		)
		(fp_line
			(start 0.67945 0.3048)
			(end 0.120396 0.3048)
			(stroke
				(width 0.1)
				(type default)
			)
			(layer "F.Fab")
		)
		(fp_line
			(start -0.12065 0.2794)
			(end -0.12065 0.3048)
			(stroke
				(width 0.1)
				(type default)
			)
			(layer "F.Fab")
		)
		(fp_line
			(start 0.120396 0.2794)
			(end -0.12065 0.2794)
			(stroke
				(width 0.1)
				(type default)
			)
			(layer "F.Fab")
		)
		(fp_line
			(start -0.12065 -0.2794)
			(end 0.12065 -0.2794)
			(stroke
				(width 0.1)
				(type default)
			)
			(layer "F.Fab")
		)
		(fp_line
			(start 0.12065 -0.2794)
			(end 0.12065 -0.3048)
			(stroke
				(width 0.1)
				(type default)
			)
			(layer "F.Fab")
		)
		(fp_line
			(start 0.12065 -0.3048)
			(end 0.67945 -0.3048)
			(stroke
				(width 0.1)
				(type default)
			)
			(layer "F.Fab")
		)
		(fp_line
			(start 0.67945 -0.3048)
			(end 0.67945 0.3048)
			(stroke
				(width 0.1)
				(type default)
			)
			(layer "F.Fab")
		)
		(fp_line
			(start -0.67945 -0.305054)
			(end -0.12065 -0.305054)
			(stroke
				(width 0.1)
				(type default)
			)
			(layer "F.Fab")
		)
		(fp_line
			(start -0.12065 -0.305054)
			(end -0.12065 -0.2794)
			(stroke
				(width 0.1)
				(type default)
			)
			(layer "F.Fab")
		)
		(pad "1" smd circle
			(at -0.40005 0 270)
			(size 0 0)
			(layers "F.Cu" "F.Mask" "F.Paste")
			(net "H_CPU_ERR0_LVC1_R_N")
		)
		(pad "2" smd circle
			(at 0.40005 0 270)
			(size 0 0)
			(layers "F.Cu" "F.Mask" "F.Paste")
			(net "H_CPU_ERR0_LVC1_N")
		)
	)
	(footprint ""
		(layer "F.Cu")
		(at 113.349532 -365.158274 90)
		(property "Reference" "PC1194"
			(at 0 0 90)
			(layer "F.SilkS")
			(hide yes)
			(effects
				(font
					(size 1.27 1.27)
				)
			)
		)
		(property "Value" ""
			(at 0 0 90)
			(layer "F.Fab")
			(effects
				(font
					(size 1.27 1.27)
				)
			)
		)
		(duplicate_pad_numbers_are_jumpers no)
		(fp_line
			(start 0.7874 -0.4064)
			(end 0.7874 0.4064)
			(stroke
				(width 0.1524)
				(type default)
			)
			(layer "F.SilkS")
		)
		(fp_line
			(start -0.7874 -0.4064)
			(end 0.7874 -0.4064)
			(stroke
				(width 0.1524)
				(type default)
			)
			(layer "F.SilkS")
		)
		(fp_line
			(start 0.7874 0.4064)
			(end -0.7874 0.4064)
			(stroke
				(width 0.1524)
				(type default)
			)
			(layer "F.SilkS")
		)
		(fp_line
			(start -0.7874 0.4064)
			(end -0.7874 -0.4064)
			(stroke
				(width 0.1524)
				(type default)
			)
			(layer "F.SilkS")
		)
		(fp_line
			(start -0.12065 -0.305054)
			(end -0.12065 -0.2794)
			(stroke
				(width 0.1)
				(type default)
			)
			(layer "F.Fab")
		)
		(fp_line
			(start -0.67945 -0.305054)
			(end -0.12065 -0.305054)
			(stroke
				(width 0.1)
				(type default)
			)
			(layer "F.Fab")
		)
		(fp_line
			(start 0.67945 -0.3048)
			(end 0.67945 0.3048)
			(stroke
				(width 0.1)
				(type default)
			)
			(layer "F.Fab")
		)
		(fp_line
			(start 0.12065 -0.3048)
			(end 0.67945 -0.3048)
			(stroke
				(width 0.1)
				(type default)
			)
			(layer "F.Fab")
		)
		(fp_line
			(start 0.12065 -0.2794)
			(end 0.12065 -0.3048)
			(stroke
				(width 0.1)
				(type default)
			)
			(layer "F.Fab")
		)
		(fp_line
			(start -0.12065 -0.2794)
			(end 0.12065 -0.2794)
			(stroke
				(width 0.1)
				(type default)
			)
			(layer "F.Fab")
		)
		(fp_line
			(start 0.120396 0.2794)
			(end -0.12065 0.2794)
			(stroke
				(width 0.1)
				(type default)
			)
			(layer "F.Fab")
		)
		(fp_line
			(start -0.12065 0.2794)
			(end -0.12065 0.3048)
			(stroke
				(width 0.1)
				(type default)
			)
			(layer "F.Fab")
		)
		(fp_line
			(start 0.67945 0.3048)
			(end 0.120396 0.3048)
			(stroke
				(width 0.1)
				(type default)
			)
			(layer "F.Fab")
		)
		(fp_line
			(start 0.120396 0.3048)
			(end 0.120396 0.2794)
			(stroke
				(width 0.1)
				(type default)
			)
			(layer "F.Fab")
		)
		(fp_line
			(start -0.12065 0.3048)
			(end -0.67945 0.3048)
			(stroke
				(width 0.1)
				(type default)
			)
			(layer "F.Fab")
		)
		(fp_line
			(start -0.67945 0.3048)
			(end -0.67945 -0.305054)
			(stroke
				(width 0.1)
				(type default)
			)
			(layer "F.Fab")
		)
		(pad "1" smd circle
			(at -0.40005 0 90)
			(size 0 0)
			(layers "F.Cu" "F.Mask" "F.Paste")
			(net "PVCCIN_CPU1_VREF")
		)
		(pad "2" smd circle
			(at 0.40005 0 90)
			(size 0 0)
			(layers "F.Cu" "F.Mask" "F.Paste")
			(net "GND")
		)
	)
	(footprint ""
		(layer "F.Cu")
		(at 327.281032 -13.746734)
		(property "Reference" "C535"
			(at 0 0 0)
			(layer "F.SilkS")
			(hide yes)
			(effects
				(font
					(size 1.27 1.27)
				)
			)
		)
		(property "Value" ""
			(at 0 0 0)
			(layer "F.Fab")
			(effects
				(font
					(size 1.27 1.27)
				)
			)
		)
		(duplicate_pad_numbers_are_jumpers no)
		(fp_line
			(start -1.524 -0.762)
			(end 1.524 -0.762)
			(stroke
				(width 0.1524)
				(type default)
			)
			(layer "F.SilkS")
		)
		(fp_line
			(start -1.524 0.762)
			(end -1.524 -0.762)
			(stroke
				(width 0.1524)
				(type default)
			)
			(layer "F.SilkS")
		)
		(fp_line
			(start 1.524 -0.762)
			(end 1.524 0.762)
			(stroke
				(width 0.1524)
				(type default)
			)
			(layer "F.SilkS")
		)
		(fp_line
			(start 1.524 0.762)
			(end -1.524 0.762)
			(stroke
				(width 0.1524)
				(type default)
			)
			(layer "F.SilkS")
		)
		(fp_line
			(start -1.1049 -0.724916)
			(end -1.1049 0.724916)
			(stroke
				(width 0.1)
				(type default)
			)
			(layer "F.Fab")
		)
		(fp_line
			(start -1.1049 0.724916)
			(end 1.1049 0.724916)
			(stroke
				(width 0.1)
				(type default)
			)
			(layer "F.Fab")
		)
		(fp_line
			(start 1.1049 -0.724916)
			(end -1.1049 -0.724916)
			(stroke
				(width 0.1)
				(type default)
			)
			(layer "F.Fab")
		)
		(fp_line
			(start 1.1049 0.724916)
			(end 1.1049 -0.724916)
			(stroke
				(width 0.1)
				(type default)
			)
			(layer "F.Fab")
		)
		(pad "1" smd rect
			(at -0.889 0 180)
			(size 1.016 1.27)
			(layers "F.Cu" "F.Mask" "F.Paste")
			(net "PGPPA_AUX")
		)
		(pad "2" smd rect
			(at 0.889 0 180)
			(size 1.016 1.27)
			(layers "F.Cu" "F.Mask" "F.Paste")
			(net "GND")
		)
	)
)
